# S9S_MB_2U (Grand Teton) — schematic parts with pin connectivity, parts 5876–5876 of 6093; source: Cadence DE-HDL packaged netlist (pstxprt.dat, pstxnet.dat, pstchip.dat)

U1  SOCKET4677_AZIF0045P001C01CS  SOCKET4677_AZIF0045-P001C01CS IO  pkg SOCKET4677_82X64-5XA_H466  page 44  (pins 655-981 of 4677)
  AP89  PE4_RX_DN11  IN  = P5E_CPU1_PE4_RX_DN<11>
  AP91  VSS281  POWER  = GND
  AR1  VSS282  POWER  = GND
  AR3  UPI0_TX_DP13  OUT  = UPI_CPU1_CPU0_P0P1_DP<13>
  AR5  VSS294  POWER  = GND
  AR7  UPI0_RX_DP12  IN  = UPI_CPU0_CPU1_P1P0_DP<12>
  AR9  VSS308  POWER  = GND
  AR11  PE0_RX_DP12  IN  = P5E_CPU1_PE0_RX_DP<12>
  AR13  VSS283  POWER  = GND
  AR15  PE0_TX_DP11  OUT  = P5E_CPU1_PE0_TX_DP<11>
  AR17  RSVD3  BI  = NC_CPU1_UPI0_APROBE<1>
  AR19  VSS284  POWER  = GND
  AR21  DDR3_SB_DQS_DP8  BI  = M_D_CPU1_SB_DQS_DP<8>
  AR23  VSS285  POWER  = GND
  AR25  VSS286  POWER  = GND
  AR27  DDR3_SB_DQS_DP6  BI  = M_D_CPU1_SB_DQS_DP<6>
  AR29  VSS287  POWER  = GND
  AR31  VSS288  POWER  = GND
  AR33  DDR3_SB_DQS_DP5  BI  = M_D_CPU1_SB_DQS_DP<5>
  AR35  VSS289  POWER  = GND
  AR37  VSS290  POWER  = GND
  AR39  DDR3_SB_DQS_DN4  BI  = M_D_CPU1_SB_DQS_DN<4>
  AR41  VSS291  POWER  = GND
  AR43  VSS292  POWER  = GND
  AR45  DDR3_CLK_DP1  OUT  = M_D_CPU1_CLK_DP<1>
  AR48  VSS293  POWER  = GND
  AR50  VSS295  POWER  = GND
  AR52  DDR3_SA_CA1  OUT  = M_D_CPU1_SA_CA<1>
  AR54  VSS296  POWER  = GND
  AR56  VSS297  POWER  = GND
  AR58  DDR3_SA_DQS_DP9  BI  = M_D_CPU1_SA_DQS_DP<9>
  AR60  VSS298  POWER  = GND
  AR62  VSS299  POWER  = GND
  AR64  DDR3_SA_DQS_DP8  BI  = M_D_CPU1_SA_DQS_DP<8>
  AR66  VSS300  POWER  = GND
  AR68  VSS301  POWER  = GND
  AR70  DDR3_SA_DQS_DP7  BI  = M_D_CPU1_SA_DQS_DP<7>
  AR72  VSS302  POWER  = GND
  AR74  VSS303  POWER  = GND
  AR76  DDR3_SA_DQS_DP6  BI  = M_D_CPU1_SA_DQS_DP<6>
  AR78  VSS304  POWER  = GND
  AR80  UPI2_TX_DN14  OUT  = UPI_CPU1_CPU0_P2P2_DN<14>
  AR82  VSS305  POWER  = GND
  AR84  VSS306  POWER  = GND
  AR86  PE4_TX_DN12  OUT  = P5E_CPU1_PE4_TX_DN<12>
  AR88  VSS307  POWER  = GND
  AR90  PE4_RX_DP12  IN  = P5E_CPU1_PE4_RX_DP<12>
  AT2  UPI0_TX_DN13  OUT  = UPI_CPU1_CPU0_P0P1_DN<13>
  AT4  VSS318  POWER  = GND
  AT6  UPI0_RX_DP13  IN  = UPI_CPU0_CPU1_P1P0_DP<13>
  AT8  VSS332  POWER  = GND
  AT10  PE0_RX_DP13  IN  = P5E_CPU1_PE0_RX_DP<13>
  AT12  VSS309  POWER  = GND
  AT14  PE0_TX_DP12  OUT  = P5E_CPU1_PE0_TX_DP<12>
  AT16  VSS310  POWER  = GND
  AT18  BIST_ENABLE  IN  = PD_CPU1_BIST_ENABLE
  AT20  VSS311  POWER  = GND
  AT22  VSS312  POWER  = GND
  AT24  RSVD4  BI  = CPU1_RSVD<4>
  AT26  VSS313  POWER  = GND
  AT28  VSS314  POWER  = GND
  AT30  BCLK0_DN  IN  = CLK_100M_DB2000_CPU1_BCLK0_DN
  AT32  VSS315  POWER  = GND
  AT34  VSS316  POWER  = GND
  AT36  VCCD_HV0  POWER  = PVCCD_HV_CPU1
  AT38  VSS317  POWER  = GND
  AT40  VSS319  POWER  = GND
  AT42  DDR0_A_RSP0  IN  = M_A_CPU1_SA_RSP<0>
  AT44  VSS320  POWER  = GND
  AT47  DDR2_ALERT_N  IN  = M_C_CPU1_ALERT_N
  AT49  DDR0_ALERT_N  IN  = M_A_CPU1_ALERT_N
  AT51  VSS321  POWER  = GND
  AT53  VSS322  POWER  = GND
  AT55  VCCD_HV1  POWER  = PVCCD_HV_CPU1
  AT57  VSS323  POWER  = GND
  AT59  VSS324  POWER  = GND
  AT61  VCCFA_EHV4  POWER  = PVCCFA_EHV_CPU1
  AT63  VSS325  POWER  = GND
  AT65  VSS326  POWER  = GND
  AT67  RSVD5  BI  = NC_CPU1_UPI2_APROBE<1>
  AT69  VSS327  POWER  = GND
  AT71  VSS328  POWER  = GND
  AT73  VCCFA_EHV_FIVRA22  POWER  = PVCCFA_EHV_FIVRA_CPU1
  AT75  VSS329  POWER  = GND
  AT77  VSS330  POWER  = GND
  AT79  VSS331  POWER  = GND
  AT81  UPI2_TX_DP14  OUT  = UPI_CPU1_CPU0_P2P2_DP<14>
  AT83  UPI2_TX_DN15  OUT  = UPI_CPU1_CPU0_P2P2_DN<15>
  AT85  VSS_VCCFA_EHV_FIVRA_SENSE  POWER  = VSENSE_PVCCFA_EHV_FIVRA_CPU1_DN
  AT87  PE4_TX_DP12  OUT  = P5E_CPU1_PE4_TX_DP<12>
  AT89  VCCFA_EHV_FIVRA23  POWER  = PVCCFA_EHV_FIVRA_CPU1
  AT91  PE4_RX_DN12  IN  = P5E_CPU1_PE4_RX_DN<12>
  AU1  UPI0_TX_DN14  OUT  = UPI_CPU1_CPU0_P0P1_DN<14>
  AU3  VCCD_HV2  POWER  = PVCCD_HV_CPU1
  AU5  UPI0_RX_DN13  IN  = UPI_CPU0_CPU1_P1P0_DN<13>
  AU7  VCCD_HV5  POWER  = PVCCD_HV_CPU1
  AU9  PE0_RX_DN13  IN  = P5E_CPU1_PE0_RX_DN<13>
  AU11  VCCFA_EHV_SENSE  POWER  = VSENSE_PVCCFA_EHV_CPU1_DP
  AU13  PE0_TX_DN12  OUT  = P5E_CPU1_PE0_TX_DN<12>
  AU15  VCCFA_EHV_FIVRA24  POWER  = PVCCFA_EHV_FIVRA_CPU1
  AU17  FRMAGENT  IN  = PU_CPU1_FRMAGENT
  AU19  PROCHOT_N  IN  = H_CPU1_PROCHOT_LVC1_N
  AU21  MEMHOT_IN_N  IN  = H_CPU1_MEMHOT_IN_LVC1_N
  AU23  SAFE_MODE_BOOT  BI  = PU_CPU1_SAFE_MODE_BOOT
  AU25  RSVD6  BI  = CPU1_RSVD<6>
  AU27  VSS333  POWER  = GND
  AU29  BCLK2_DN  IN  = CLK_100M_DB2000_CPU1_BCLK2_DN
  AU31  VSS334  POWER  = GND
  AU33  RSVD7  BI  = NC_CPU1_DDR23_VIEWDIG1
  AU35  VCCD_HV3  POWER  = PVCCD_HV_CPU1
  AU37  VSS335  POWER  = GND
  AU39  VSS336  POWER  = GND
  AU41  VSS337  POWER  = GND
  AU43  DDR0_A_RSP1  IN  = M_A_CPU1_SA_RSP<1>
  AU45  VSS338  POWER  = GND
  AU48  VSS339  POWER  = GND
  AU50  DDR01_RESET_N  OUT  = RST_CPU1_DRAM_AB_N
  AU52  RSVD8  BI  = TP_CPU1_SPARE5
  AU54  VCCD_HV4  POWER  = PVCCD_HV_CPU1
  AU56  RSVD9  BI  = NC_CPU1_DDR01_VIEWDIG1
  AU58  RSVD10  BI  = NC_CPU1_DDR01_VIEWDIG0
  AU60  VCCFA_EHV5  POWER  = PVCCFA_EHV_CPU1
  AU62  RSVD11  BI  = NC_SPI_CPU1_NCM_CLK
  AU64  RSVD12  BI  = NC_ESPI_IBL_CPU1_IO2
  AU66  RSVD13  BI  = NC_CPU1_PE4_APROBE<1>
  AU68  RSVD14  BI  = NC_CPU1_UPI2_APROBE<0>
  AU70  VSS340  POWER  = GND
  AU72  VSS341  POWER  = GND
  AU74  VSS342  POWER  = GND
  AU76  VSS343  POWER  = GND
  AU78  UPI2_TX_DN11  OUT  = UPI_CPU1_CPU0_P2P2_DN<11>
  AU80  VSS344  POWER  = GND
  AU82  UPI2_TX_DP16  OUT  = UPI_CPU1_CPU0_P2P2_DP<16>
  AU84  VSS345  POWER  = GND
  AU86  PE4_TX_DN13  OUT  = P5E_CPU1_PE4_TX_DN<13>
  AU88  VSS346  POWER  = GND
  AU90  PE4_RX_DP13  IN  = P5E_CPU1_PE4_RX_DP<13>
  AV2  UPI0_TX_DP14  OUT  = UPI_CPU1_CPU0_P0P1_DP<14>
  AV4  VSS349  POWER  = GND
  AV6  UPI0_RX_DN14  IN  = UPI_CPU0_CPU1_P1P0_DN<14>
  AV8  VSS351  POWER  = GND
  AV10  PE0_RX_DN14  IN  = P5E_CPU1_PE0_RX_DN<14>
  AV12  VSS347  POWER  = GND
  AV14  PE0_TX_DN13  OUT  = P5E_CPU1_PE0_TX_DN<13>
  AV16  VSS348  POWER  = GND
  AV18  NMI  IN  = H_CPU1_NMI_LVC1_N
  AV20  PWRGOOD  IN  = PWRGD_CPU1_LVC1
  AV22  PREQ_N  IN  = H_CPU1_PREQ_QS_GTL_R_N
  AV24  MEMTRIP_N  OUT  = H_CPU1_MEMTRIP_LVC1_R_N
  AV26  RSVD15  BI  = CPU1_RSVD<15>
  AV28  BCLK2_DP  IN  = CLK_100M_DB2000_CPU1_BCLK2_DP
  AV30  BCLK0_DP  IN  = CLK_100M_DB2000_CPU1_BCLK0_DP
  AV32  RSVD16  BI  = NC_CPU1_DDR23_VIEWDIG0
  AV34  VCCD_HV6  POWER  = PVCCD_HV_CPU1
  AV36  VCCD_HV7  POWER  = PVCCD_HV_CPU1
  AV38  RSVD17  BI  = NC_CPU1_THERMADC
  AV40  RSVD18  BI  = NC_CPU1_THERMADA
  AV42  DDR0_B_RSP1  IN  = M_A_CPU1_SB_RSP<1>
  AV44  DDR0_B_RSP0  IN  = M_A_CPU1_SB_RSP<0>
  AV47  DDR3_ALERT_N  IN  = M_D_CPU1_ALERT_N
  AV49  DDR1_ALERT_N  IN  = M_B_CPU1_ALERT_N
  AV51  DDR23_RESET_N  OUT  = RST_CPU1_DRAM_CD_N
  AV53  VCCD_HV8  POWER  = PVCCD_HV_CPU1
  AV55  VCCD_HV9  POWER  = PVCCD_HV_CPU1
  AV57  FBRK_N  IN  = FM_CPU_FBRK_DEBUG_R_N
  AV59  RSVD19  BI  = TP_EV_CPU1_EXT_BGREF
  AV61  VCCFA_EHV6  POWER  = PVCCFA_EHV_CPU1
  AV63  RSVD20  BI  = NC_SPI_S3M_CPU1_CS1_LVC1_R_N
  AV65  RSVD21  BI  = NC_CPU1_MDFI_DIE01_EW0
  AV67  RSVD22  BI  = NC_CPU1_PE4_APROBE<0>
  AV69  TEST_7  BI  = FM_S3M_CPU1_LVC1_GPIO_2
  AV71  PARTITION_ID1  IN  = FM_S3M_CPU1_LVC1_GPIO_1
  AV73  UPI2_RX_DN13  IN  = UPI_CPU0_CPU1_P2P2_DN<13>
  AV75  UPI2_RX_DP16  IN  = UPI_CPU0_CPU1_P2P2_DP<16>
  AV77  VSS350  POWER  = GND
  AV79  UPI2_TX_DP11  OUT  = UPI_CPU1_CPU0_P2P2_DP<11>
  AV81  UPI2_TX_DN16  OUT  = UPI_CPU1_CPU0_P2P2_DN<16>
  AV83  UPI2_TX_DP15  OUT  = UPI_CPU1_CPU0_P2P2_DP<15>
  AV85  PE4_TX_DP13  OUT  = P5E_CPU1_PE4_TX_DP<13>
  AV87  VSS352  POWER  = GND
  AV89  PE4_RX_DN13  IN  = P5E_CPU1_PE4_RX_DN<13>
  AV91  VSS353  POWER  = GND
  AW1  VSS354  POWER  = GND
  AW3  UPI0_TX_DP15  OUT  = UPI_CPU1_CPU0_P0P1_DP<15>
  AW5  VSS359  POWER  = GND
  AW7  UPI0_RX_DP14  IN  = UPI_CPU0_CPU1_P1P0_DP<14>
  AW9  VSS368  POWER  = GND
  AW11  PE0_RX_DP14  IN  = P5E_CPU1_PE0_RX_DP<14>
  AW13  VSS355  POWER  = GND
  AW15  PE0_TX_DP13  OUT  = P5E_CPU1_PE0_TX_DP<13>
  AW17  DMIMODE_OVERRIDE  IN  = PD_CPU1_DMIMODE_OVERRIDE
  AW19  RSVD23  BI  = TP_FM_WAKE_CPU1_N
  AW21  VSS356  POWER  = GND
  AW23  VSS357  POWER  = GND
  AW25  VSS358  POWER  = GND
  AW60  VCCFA_EHV7  POWER  = PVCCFA_EHV_CPU1
  AW62  VSS360  POWER  = GND
  AW64  RSVD24  BI  = NC_SPI_S3M_CPU1_IO1_LVC1_R
  AW66  VSS361  POWER  = GND
  AW68  VSS362  POWER  = GND
  AW70  RSVD25  BI  = FM_S3M_CPU1_LVC1_GPIO_4
  AW72  VSS363  POWER  = GND
  AW74  UPI2_RX_DN16  IN  = UPI_CPU0_CPU1_P2P2_DN<16>
  AW76  VCCFA_EHV_FIVRA25  POWER  = PVCCFA_EHV_FIVRA_CPU1
  AW78  UPI2_TX_DN10  OUT  = UPI_CPU1_CPU0_P2P2_DN<10>
  AW80  VSS364  POWER  = GND
  AW82  VSS365  POWER  = GND
  AW84  VSS366  POWER  = GND
  AW86  PE4_TX_DN14  OUT  = P5E_CPU1_PE4_TX_DN<14>
  AW88  VSS367  POWER  = GND
  AW90  PE4_RX_DP14  IN  = P5E_CPU1_PE4_RX_DP<14>
  AY2  UPI0_TX_DN15  OUT  = UPI_CPU1_CPU0_P0P1_DN<15>
  AY4  VSS371  POWER  = GND
  AY6  UPI0_RX_DP15  IN  = UPI_CPU0_CPU1_P1P0_DP<15>
  AY8  VSS375  POWER  = GND
  AY10  PE0_RX_DP15  IN  = P5E_CPU1_PE0_RX_DP<15>
  AY12  VSS369  POWER  = GND
  AY14  PE0_TX_DP14  OUT  = P5E_CPU1_PE0_TX_DP<14>
  AY16  VSS370  POWER  = GND
  AY18  VCCINFAON33  POWER  = PVCCINFAON_CPU1
  AY20  TAP_ODT_EN  IN  = PU_TAP_ODT_CPU1_EN
  AY22  ERROR_N1  OUT  = H_CPU1_ERR1_LVC1_R_N
  AY24  RSVD26  BI  = NC_CPU1_SOC_SPARE0
  AY26  RSVD27  BI  = CPU1_RSVD<25>
  AY61  RSVD28  BI  = NC_SPI_CPU1_NCM_IO1
  AY63  PKG_ID1  IN  = FM_CPU1_PKGID1
  AY65  RSVD29  BI  = CPU1_RSVD<27>
  AY67  RSVD30  BI  = NC_SPI_CPU1_NCM_CS0_N
  AY69  TEST_8  BI  = FM_S3M_CPU1_LVC1_GPIO_3
  AY71  VSS372  POWER  = GND
  AY73  UPI2_RX_DP13  IN  = UPI_CPU0_CPU1_P2P2_DP<13>
  AY75  UPI2_RX_DN14  IN  = UPI_CPU0_CPU1_P2P2_DN<14>
  AY77  VSS373  POWER  = GND
  AY79  VSS374  POWER  = GND
  AY81  VSS376  POWER  = GND
  AY83  VSS377  POWER  = GND
  AY85  VCCFA_EHV_FIVRA_SENSE  POWER  = VSENSE_PVCCFA_EHV_FIVRA_CPU1_DP
  AY87  PE4_TX_DP14  OUT  = P5E_CPU1_PE4_TX_DP<14>
  AY89  VCCFA_EHV_FIVRA26  POWER  = PVCCFA_EHV_FIVRA_CPU1
  AY91  PE4_RX_DN14  IN  = P5E_CPU1_PE4_RX_DN<14>
  B6  VSS387  POWER  = GND
  B8  DDR0_SB_DQ28  BI  = M_A_CPU1_SB_DQ<28>
  B10  DDR0_SB_DQ25  BI  = M_A_CPU1_SB_DQ<25>
  B12  VSS378  POWER  = GND
  B14  DDR1_SB_DQ30  BI  = M_B_CPU1_SB_DQ<30>
  B16  DDR1_SB_DQ25  BI  = M_B_CPU1_SB_DQ<25>
  B18  VSS379  POWER  = GND
  B20  DDR0_SB_DQ20  BI  = M_A_CPU1_SB_DQ<20>
  B22  DDR0_SB_DQ17  BI  = M_A_CPU1_SB_DQ<17>
  B24  VSS380  POWER  = GND
  B26  DDR0_SB_DQ12  BI  = M_A_CPU1_SB_DQ<12>
  B28  DDR0_SB_DQ9  BI  = M_A_CPU1_SB_DQ<9>
  B30  VSS381  POWER  = GND
  B32  DDR0_SB_ECC0  BI  = M_A_CPU1_SB_CB<0>
  B34  DDR0_SB_ECC5  BI  = M_A_CPU1_SB_CB<5>
  B36  VSS382  POWER  = GND
  B38  DDR0_SB_CS_N0  OUT  = M_A_CPU1_SB_CS_N<0>
  B40  DDR0_SB_CA4  OUT  = M_A_CPU1_SB_CA<4>
  B42  VSS384  POWER  = GND
  B44  DDR0_CLK_DN0  OUT  = M_A_CPU1_CLK_DN<0>
  B49  VSS385  POWER  = GND
  B51  DDR0_SA_CA2  OUT  = M_A_CPU1_SA_CA<2>
  B53  DDR0_SA_CS_N1  OUT  = M_A_CPU1_SA_CS_N<1>
  B55  VSS386  POWER  = GND
  B57  DDR0_SA_ECC4  BI  = M_A_CPU1_SA_CB<4>
  B59  DDR0_SA_ECC1  BI  = M_A_CPU1_SA_CB<1>
  B61  VSS388  POWER  = GND
  B63  DDR0_SA_DQ28  BI  = M_A_CPU1_SA_DQ<28>
  B65  DDR0_SA_DQ25  BI  = M_A_CPU1_SA_DQ<25>
  B67  VSS389  POWER  = GND
  B69  DDR0_SA_DQ20  BI  = M_A_CPU1_SA_DQ<20>
  B71  DDR0_SA_DQS_DN2  BI  = M_A_CPU1_SA_DQS_DN<2>
  B73  DDR0_SA_DQ16  BI  = M_A_CPU1_SA_DQ<16>
  B75  VSS390  POWER  = GND
  B77  DDR0_SA_DQS_DN0  BI  = M_A_CPU1_SA_DQS_DN<0>
  B79  DDR0_SA_DQ1  BI  = M_A_CPU1_SA_DQ<1>
  B81  DDR0_SA_DQ0  BI  = M_A_CPU1_SA_DQ<0>
  B83  VSS391  POWER  = GND
  B85  UPI2_TX_DN0  OUT  = UPI_CPU1_CPU0_P2P2_DN<0>
  B87  VSS392  POWER  = GND
  BA1  UPI0_TX_DP16  OUT  = UPI_CPU1_CPU0_P0P1_DP<16>
  BA3  VCCD_HV10  POWER  = PVCCD_HV_CPU1
  BA5  UPI0_RX_DN15  IN  = UPI_CPU0_CPU1_P1P0_DN<15>
  BA7  VCCD_HV11  POWER  = PVCCD_HV_CPU1
  BA9  PE0_RX_DN15  IN  = P5E_CPU1_PE0_RX_DN<15>
  BA11  VSS_VCCFA_EHV_SENSE  POWER  = VSENSE_PVCCFA_EHV_CPU1_DN
  BA13  PE0_TX_DN14  OUT  = P5E_CPU1_PE0_TX_DN<14>
  BA15  VCCINFAON34  POWER  = PVCCINFAON_CPU1
  BA17  VSS393  POWER  = GND
  BA19  VCCVNN0  POWER  = PVNN_MAIN_CPU1
  BA21  VCC_3P3_AUX1  POWER  = P3V3_AUX
  BA23  UPI0_AC_COUPLING  IN  = PU_CPU1_UPI0_AC_COUPLING
  BA25  RSVD31  BI  = NC_CPU1_SOC_SPARE4
  BA60  VSS394  POWER  = GND
  BA62  RSVD32  BI  = NC_SPI_S3M_CPU1_IO0_LVC1_R
  BA64  VSS395  POWER  = GND
  BA66  RSVD33  BI  = NC_SPI_CPU1_NCM_IO0
  BA68  RSVD34  BI  = NC_SPI_S3M_CPU1_OE_LVC1_R_N
  BA70  PARTITION_ID0  IN  = FM_S3M_CPU1_LVC1_GPIO_0
  BA72  UPI2_RX_DN12  IN  = UPI_CPU0_CPU1_P2P2_DN<12>
  BA74  VSS397  POWER  = GND
  BA76  UPI2_RX_DP14  IN  = UPI_CPU0_CPU1_P2P2_DP<14>
  BA78  UPI2_TX_DP10  OUT  = UPI_CPU1_CPU0_P2P2_DP<10>
  BA80  UPI2_TX_DN17  OUT  = UPI_CPU1_CPU0_P2P2_DN<17>
  BA82  UPI2_TX_DP18  OUT  = UPI_CPU1_CPU0_P2P2_DP<18>
  BA84  VSS398  POWER  = GND
  BA86  PE4_TX_DN15  OUT  = P5E_CPU1_PE4_TX_DN<15>
  BA88  VSS399  POWER  = GND
  BA90  PE4_RX_DP15  IN  = P5E_CPU1_PE4_RX_DP<15>
  BB2  UPI0_TX_DN16  OUT  = UPI_CPU1_CPU0_P0P1_DN<16>
  BB4  VSS407  POWER  = GND
  BB6  UPI0_RX_DN16  IN  = UPI_CPU0_CPU1_P1P0_DN<16>
  BB8  VSS413  POWER  = GND
  BB10  VSS400  POWER  = GND
  BB12  VSS401  POWER  = GND
  BB14  PE0_TX_DN15  OUT  = P5E_CPU1_PE0_TX_DN<15>
  BB16  VSS402  POWER  = GND
  BB18  DMI_RX_DN0  IN  = TP_DMI_CPU1_PCH_RX_C_DN<0>
  BB20  VSS403  POWER  = GND
  BB22  VSS404  POWER  = GND
  BB24  VSS405  POWER  = GND
  BB26  VSS406  POWER  = GND
  BB61  RSVD35  BI  = NC_SPI_S3M_CPU1_CS0_LVC1_R_N
  BB63  VSS408  POWER  = GND
  BB65  UPI2_AC_COUPLING  IN  = PU_CPU1_UPI2_AC_COUPLING
  BB67  RSVD36  BI  = NC_SPI_CPU1_NCM_OE_N
  BB69  VSS409  POWER  = GND
